FILE_TYPE = CONNECTIVITY;
{Allegro Design Entry HDL 17.4-2019 S026 (4007227) 1/17/2022}
"PAGE_NUMBER" = 380;
0"NC";
1"GND\g";
2"GND\g";
3"GND\g";
4"GND\g";
5"P3V3_AUX\g";
6"GND\g";
7"GND\g";
8"GND\g";
9"PWRGD_P1V8_AUX_R";
10"PWRGD_P1V2_AUX";
11"SW_P1V2_AUX_BT_R";
12"SW_P1V2_AUX_PH";
13"SW_P1V2_AUX_BT";
14"P12V_AUX\g";
15"GND\g";
16"GND\g";
17"P1V2_AUX\g";
18"P3V3_AUX\g";
19"GND\g";
20"GND\g";
21"PWRGD_P1V2_AUX_R";
22"P1V2_AUX_FB";
23"P1V2_AUX_MODE";
24"P1V2_AUX_ENABLE";
25"P1V2_AUX_VCC";
26"SW_P12V_AUX_P1V2_AUX_FLT";
27"P1V2_AUX_CS";
28"P1V2_AUX_REF";
%"GND"
"1","(-5600,750)","0","pure_quanta_power","I1";
;
CDS_LIB"pure_quanta_power"
SIZE"1B"
HDL_POWER"GND";
"A<SIZE-1..0>\NAC"1;
%"Q_CAP"
"1","(-6300,2500)","0","pure_quanta","I10";
;
LOCATION"PC6015"
$SEC"1"
CDS_SEC"1"
TOLERANCE"20%"
VALUE"22UF"
VOLTAGE"16V"
MATERIAL"X6S"
PACK_TYPE"C0805"
CDS_LIB"pure_quanta"
PART_NUMBER"CH6223MEA01";
"B"
$PN"2"20;
"A"
$PN"1"26;
%"Q_RES"
"1","(-5875,1800)","0","pure_quanta","I11";
;
LOCATION"PR6005"
$SEC"1"
CDS_SEC"1"
WATTAGE"1/16W"
MATERIAL"CHIP"
PACK_TYPE"0402LF"
TOLERANCE"1%"
VALUE"60.4K"
CDS_LIB"pure_quanta"
PART_NUMBER"CS36042FB04";
"B"
$PN"2"23;
"A"
$PN"1"19;
%"Q_CAP"
"1","(-5700,2500)","0","pure_quanta","I12";
;
LOCATION"PC6011"
$SEC"1"
CDS_SEC"1"
VALUE"1UF"
VOLTAGE"25V"
TOLERANCE"10%"
MATERIAL"X6S"
PACK_TYPE"C0402"
CDS_LIB"pure_quanta"
PART_NUMBER"CH5104KEB02";
"B"
$PN"2"20;
"A"
$PN"1"26;
%"UNIVERSAL_POWER"
"1","(-7700,2850)","0","pure_quanta_power","I13";
;
HDL_POWER"P12V_AUX"
CDS_LIB"pure_quanta_power";
"A"14;
%"GND"
"1","(-3700,750)","0","pure_quanta_power","I14";
;
CDS_LIB"pure_quanta_power"
SIZE"1B"
HDL_POWER"GND";
"A<SIZE-1..0>\NAC"2;
%"GND"
"1","(-4100,750)","0","pure_quanta_power","I15";
;
CDS_LIB"pure_quanta_power"
SIZE"1B"
HDL_POWER"GND";
"A<SIZE-1..0>\NAC"15;
%"MPQ8626GDZ"
"1","(-4650,1825)","0","pure_quanta","I16";
;
LOCATION"PU6001"
SEC"1"
PART_TYPE"SMLF"
MATERIAL"IC"
VALUE"MPQ8626GD-Z"
NEEDS_NO_SIZE"TRUE"
CDS_LMAN_SYM_OUTLINE"-250,725,250,-725"
CDS_LIB"pure_quanta"
SEC_TYPE""
PART_NUMBER"AL008626000";
"SW1"
$PN"2"12;
"CS"
$PN"4"27;
"MODE"
$PN"12"23;
"TRK_REF"
$PN"8"28;
"SW2"
$PN"11"12;
"PGND1"
$PN"1"4;
"VCC"
$PN"13"25;
"AGND"
$PN"7"15;
"FB"
$PN"6"22;
"BST"
$PN"10"13;
"EN"
$PN"5"24;
"PGND2"
$PN"14"15;
"PGOOD"
$PN"9"10;
"VIN"
$PN"3"26;
%"Q_CAP"
"1","(-3700,1025)","0","pure_quanta","I17";
;
LOCATION"PC6016"
$SEC"1"
CDS_SEC"1"
VALUE"3300PF"
PACK_TYPE"0402"
VOLTAGE"50V"
TOLERANCE"10%"
MATERIAL"X7R"
CDS_LIB"pure_quanta"
PART_NUMBER"TMP_QCH2336K1B12";
"B"
$PN"2"2;
"A"
$PN"1"28;
%"Q_CAP"
"1","(-3200,2175)","0","pure_quanta","I18";
;
LOCATION"PC6017"
$SEC"1"
CDS_SEC"1"
VALUE"0.22UF"
VOLTAGE"25V"
TOLERANCE"10%"
MATERIAL"X7R"
PACK_TYPE"C0402"
CDS_LIB"pure_quanta"
PART_NUMBER"CH4224K1B01";
"B"
$PN"2"12;
"A"
$PN"1"11;
%"Q_RES"
"2","(-3550,2800)","0","pure_quanta","I19";
;
LOCATION"R6244"
$SEC"1"
CDS_SEC"1"
MATERIAL"CHIP"
PACK_TYPE"0402LF"
VALUE"10K"
TOLERANCE"1%"
WATTAGE"1/16W"
CDS_LIB"pure_quanta"
PART_NUMBER"CS31002FB08";
"A"
$PN"1"5;
"B"
$PN"2"10;
%"Q_INDUCTOR"
"1","(-7200,2725)","0","pure_quanta","I2";
;
LOCATION"PL6003"
$SEC"1"
CDS_SEC"1"
PACK_TYPE"SMLF"
MATERIAL"IND"
VALUE"BLM18SN220TN1D/8000MA"
NEEDS_NO_SIZE"TRUE"
CDS_LIB"pure_quanta"
PART_NUMBER"CX220TN1001";
"1"
$PN"1"14;
"2"
$PN"2"26;
%"GND"
"1","(-3100,650)","0","pure_quanta_power","I20";
;
CDS_LIB"pure_quanta_power"
SIZE"1B"
HDL_POWER"GND";
"A<SIZE-1..0>\NAC"3;
%"Q_RES"
"2","(-3100,875)","0","pure_quanta","I21";
;
LOCATION"PR6011"
$SEC"1"
CDS_SEC"1"
MATERIAL"CHIP"
WATTAGE"1/16W"
VALUE"10K"
PACK_TYPE"0402LF"
TOLERANCE"1%"
CDS_LIB"pure_quanta"
PART_NUMBER"CS31002FB08";
"A"
$PN"1"22;
"B"
$PN"2"3;
%"GND"
"1","(-3400,1250)","0","pure_quanta_power","I22";
;
CDS_LIB"pure_quanta_power"
SIZE"1B"
HDL_POWER"GND";
"A<SIZE-1..0>\NAC"4;
%"Q_CAP"
"1","(-2550,1800)","0","pure_quanta","I23";
;
LOCATION"PC6022"
$SEC"1"
CDS_SEC"1"
PACK_TYPE"C0402"
MATERIAL"X7R"
TOLERANCE"10%"
VOLTAGE"50V"
VALUE"100NF"
CDS_LIB"pure_quanta"
PART_NUMBER"CH4106K1B01";
"B"
$PN"2"16;
"A"
$PN"1"17;
%"Q_INDUCTOR"
"1","(-2725,2025)","0","pure_quanta","I24";
;
LOCATION"PL6001"
$SEC"1"
CDS_SEC"1"
MATERIAL"IND"
PACK_TYPE"SMLF"
VALUE"2.2UH"
CDS_LIB"pure_quanta"
NEEDS_NO_SIZE"TRUE"
PART_NUMBER"CV-2280MZ15";
"1"
$PN"1"12;
"2"
$PN"2"17;
%"Q_CAP"
"2","(-2050,800)","0","pure_quanta","I26";
;
LOCATION"PC852"
$SEC"1"
CDS_SEC"1"
MATERIAL"X7R"
VOLTAGE"50V"
PACK_TYPE"0402"
VALUE"330PF"
TOLERANCE"10%"
CDS_LIB"pure_quanta"
PART_NUMBER"CH1336K1B02";
"A"
$PN"1"22;
"B"
$PN"2"17;
%"Q_RES"
"1","(-2050,1225)","0","pure_quanta","I27";
;
LOCATION"PR6008"
$SEC"1"
CDS_SEC"1"
WATTAGE"1/16W"
TOLERANCE"1%"
VALUE"10K"
PACK_TYPE"0402LF"
MATERIAL"CHIP"
CDS_LIB"pure_quanta"
PART_NUMBER"CS31002FB08";
"B"
$PN"2"17;
"A"
$PN"1"22;
%"Q_CAP"
"1","(-2150,1800)","0","pure_quanta","I28";
;
LOCATION"PC6024"
$SEC"1"
CDS_SEC"1"
MATERIAL"X6S"
TOLERANCE"20%"
VOLTAGE"4V"
VALUE"22UF"
PACK_TYPE"C0805"
CDS_LIB"pure_quanta"
PART_NUMBER"CH622KMEA03";
"B"
$PN"2"16;
"A"
$PN"1"17;
%"Q_CAP"
"1","(-1725,1800)","0","pure_quanta","I29";
;
LOCATION"PC6025"
$SEC"1"
CDS_SEC"1"
VALUE"22UF"
TOLERANCE"20%"
MATERIAL"X6S"
PACK_TYPE"C0805"
VOLTAGE"4V"
CDS_LIB"pure_quanta"
PART_NUMBER"CH622KMEA03";
"B"
$PN"2"16;
"A"
$PN"1"17;
%"Q_CAP"
"1","(-6900,2500)","0","pure_quanta","I3";
;
LOCATION"PC6013"
$SEC"1"
CDS_SEC"1"
MATERIAL"X6S"
TOLERANCE"20%"
VOLTAGE"16V"
VALUE"22UF"
PACK_TYPE"C0805"
CDS_LIB"pure_quanta"
PART_NUMBER"CH6223MEA01";
"B"
$PN"2"20;
"A"
$PN"1"26;
%"GND"
"1","(-1500,1450)","0","pure_quanta_power","I30";
;
CDS_LIB"pure_quanta_power"
SIZE"1B"
HDL_POWER"GND";
"A<SIZE-1..0>\NAC"16;
%"UNIVERSAL_POWER"
"1","(-3550,3100)","0","pure_quanta_power","I31";
;
HDL_POWER"P3V3_AUX"
CDS_LIB"pure_quanta_power";
"A"5;
%"Q_CAP"
"1","(-1300,1800)","0","pure_quanta","I32";
;
LOCATION"PC6026"
$SEC"1"
CDS_SEC"1"
VOLTAGE"4V"
PACK_TYPE"C0805"
MATERIAL"X6S"
TOLERANCE"20%"
VALUE"22UF"
CDS_LIB"pure_quanta"
PART_NUMBER"CH622KMEA03";
"B"
$PN"2"16;
"A"
$PN"1"17;
%"Q_CAP"
"1","(-800,1800)","0","pure_quanta","I33";
;
LOCATION"PC6018"
$SEC"1"
CDS_SEC"1"
VOLTAGE"4V"
TOLERANCE"20%"
PACK_TYPE"C0805"
VALUE"22UF"
MATERIAL"X6S"
CDS_LIB"pure_quanta"
PART_NUMBER"CH622KMEA03";
"B"
$PN"2"16;
"A"
$PN"1"17;
%"UNIVERSAL_POWER"
"1","(-1300,2150)","0","pure_quanta_power","I34";
;
HDL_POWER"P1V2_AUX"
CDS_LIB"pure_quanta_power";
"A"17;
%"Q_CAP"
"1","(-7700,2500)","0","pure_quanta","I35";
;
LOCATION"PC6023"
$SEC"1"
CDS_SEC"1"
VALUE"100NF"
VOLTAGE"50V"
MATERIAL"X7R"
TOLERANCE"10%"
PACK_TYPE"C0402"
CDS_LIB"pure_quanta"
PART_NUMBER"CH4106K1B01";
"B"
$PN"2"6;
"A"
$PN"1"14;
%"GND"
"1","(-7700,2250)","0","pure_quanta_power","I36";
;
CDS_LIB"pure_quanta_power"
SIZE"1B"
HDL_POWER"GND";
"A<SIZE-1..0>\NAC"6;
%"UNIVERSAL_POWER"
"1","(-6775,1700)","0","pure_quanta_power","I37";
;
HDL_POWER"P3V3_AUX"
CDS_LIB"pure_quanta_power";
"A"18;
%"Q_RES"
"2","(-6400,1550)","3","pure_quanta","I38";
;
LOCATION"R6245"
$SEC"1"
CDS_SEC"1"
WATTAGE"1/16W"
TOLERANCE"5%"
PACK_TYPE"0402LF"
VALUE"0"
MATERIAL"CHIP"
CDS_LIB"pure_quanta"
PART_NUMBER"CS00002JB13";
"A"
$PN"1"18;
"B"
$PN"2"25;
%"GND"
"1","(-6300,1650)","0","pure_quanta_power","I4";
;
CDS_LIB"pure_quanta_power"
SIZE"1B"
HDL_POWER"GND";
"A<SIZE-1..0>\NAC"19;
%"Q_RES"
"1","(-6475,2000)","0","pure_quanta","I40";
;
LOCATION"R6240"
$SEC"1"
CDS_SEC"1"
MATERIAL"CHIP"
WATTAGE"1/16W"
VALUE"0"
TOLERANCE"5%"
PACK_TYPE"0402LF"
CDS_LIB"pure_quanta"
PART_NUMBER"CS00002JB13";
"B"
$PN"2"24;
"A"
$PN"1"9;
%"Q_CAP"
"1","(-7175,1675)","2","pure_quanta","I41";
;
LOCATION"C6085"
$SEC"1"
CDS_SEC"1"
TOLERANCE"10%"
PACK_TYPE"0402"
MATERIAL"EMPTY"
VALUE"0.1UF"
VOLTAGE"25V"
CDS_LIB"pure_quanta"
PART_NUMBER"CH4104K1B00";
"B"
$PN"2"7;
"A"
$PN"1"9;
%"GND"
"1","(-7175,1250)","0","pure_quanta_power","I42";
;
SIZE"1B"
CDS_LIB"pure_quanta_power"
HDL_POWER"GND";
"A<SIZE-1..0>\NAC"7;
%"Q_RES"
"1","(-2875,2500)","0","pure_quanta","I44";
;
LOCATION"R6241"
$SEC"1"
CDS_SEC"1"
TOLERANCE"5%"
PACK_TYPE"0402LF"
VALUE"0"
MATERIAL"CHIP"
WATTAGE"1/16W"
CDS_LIB"pure_quanta"
PART_NUMBER"CS00002JB13";
"B"
$PN"2"21;
"A"
$PN"1"10;
%"Q_RES"
"1","(-3675,2300)","0","pure_quanta","I45";
;
LOCATION"PR8004"
SEC"1"
VALUE"2.2"
PACK_TYPE"0402LF"
TOLERANCE"1%"
MATERIAL"CHIP"
SEC_TYPE"0402LF"
CDS_LIB"pure_quanta"
WATTAGE"1/16W"
PART_NUMBER"CS-2202FB01";
"B"
$PN"2"11;
"A"
$PN"1"13;
%"GND"
"1","(-5800,1150)","0","pure_quanta_power","I5";
;
CDS_LIB"pure_quanta_power"
SIZE"1B"
HDL_POWER"GND";
"A<SIZE-1..0>\NAC"8;
%"Q_RES"
"2","(-5600,950)","0","pure_quanta","I6";
;
LOCATION"PR6004"
$SEC"1"
CDS_SEC"1"
PACK_TYPE"0402LF"
WATTAGE"1/16W"
MATERIAL"CHIP"
TOLERANCE"1%"
VALUE"11.5K"
CDS_LIB"pure_quanta"
PART_NUMBER"CS31152FB03";
"A"
$PN"1"27;
"B"
$PN"2"1;
%"Q_CAP"
"1","(-5800,1350)","0","pure_quanta","I7";
;
LOCATION"PC6009"
$SEC"1"
CDS_SEC"1"
VALUE"1UF"
MATERIAL"X6S"
VOLTAGE"25V"
PACK_TYPE"C0402"
TOLERANCE"10%"
CDS_LIB"pure_quanta"
PART_NUMBER"CH5104KEB02";
"B"
$PN"2"8;
"A"
$PN"1"25;
%"GND"
"1","(-6250,2150)","0","pure_quanta_power","I8";
;
CDS_LIB"pure_quanta_power"
SIZE"1B"
HDL_POWER"GND";
"A<SIZE-1..0>\NAC"20;
END.
